(kicad_pcb
	(version 20260206)
	(generator "pcbnew")
	(generator_version "10.0")
	(general
		(thickness 1.6)
		(legacy_teardrops no)
	)
	(paper "A4")
	(title_block
		(title "04192023_DAF0TMB3IC0_F0TG_MB_C_brd_V02_OCP.brd")
		(comment 1 "Grand Teton / footprints 6797-6801 of 8354")
	)
	(layers
		(0 "F.Cu" signal "TOP")
		(4 "In1.Cu" signal "GND")
		(6 "In2.Cu" signal "IN1")
		(8 "In3.Cu" signal "GND1")
		(10 "In4.Cu" signal "IN2")
		(12 "In5.Cu" signal "GND2")
		(14 "In6.Cu" signal "IN3")
		(16 "In7.Cu" signal "GND3")
		(18 "In8.Cu" signal "VCC")
		(20 "In9.Cu" signal "VCC1")
		(22 "In10.Cu" signal "GND4")
		(24 "In11.Cu" signal "IN4")
		(26 "In12.Cu" signal "GND5")
		(28 "In13.Cu" signal "IN5")
		(30 "In14.Cu" signal "GND6")
		(32 "In15.Cu" signal "IN6")
		(34 "In16.Cu" signal "GND7")
		(2 "B.Cu" signal "BOTTOM")
		(9 "F.Adhes" user "F.Adhesive")
		(11 "B.Adhes" user "B.Adhesive")
		(13 "F.Paste" user "Package Geometry/Pastemask Top")
		(15 "B.Paste" user "Package Geometry/Pastemask Bottom")
		(5 "F.SilkS" user "Ref Des/Silkscreen Top")
		(7 "B.SilkS" user "Ref Des/Silkscreen Bottom")
		(1 "F.Mask" user "Board Geometry/Soldermask Top")
		(3 "B.Mask" user "Board Geometry/Soldermask Bottom")
		(17 "Dwgs.User" user "User.Drawings")
		(19 "Cmts.User" user "User.Comments")
		(21 "Eco1.User" user "User.Eco1")
		(23 "Eco2.User" user "User.Eco2")
		(25 "Edge.Cuts" user "Board Geometry/Outline")
		(27 "Margin" user)
		(31 "F.CrtYd" user "Package Geometry/Place Bound Top")
		(29 "B.CrtYd" user "Package Geometry/Place Bound Bottom")
		(35 "F.Fab" user "Ref Des/Assembly Top")
		(33 "B.Fab" user "Ref Des/Assembly Bottom")
	)
	(footprint ""
		(layer "B.Cu")
		(at 366.288574 2.542794)
		(property "Reference" "J64"
			(at 4.258818 1.085596 270)
			(unlocked yes)
			(layer "B.SilkS")
			(effects
				(font
					(size 0.7874 0.5842)
					(thickness 0.1524)
				)
				(justify left mirror)
			)
		)
		(property "Value" ""
			(at 0 0 0)
			(layer "B.Fab")
			(effects
				(font
					(size 1.27 1.27)
				)
				(justify mirror)
			)
		)
		(duplicate_pad_numbers_are_jumpers no)
		(fp_line
			(start -1.2192 -2.06756)
			(end -1.2192 2.06756)
			(stroke
				(width 0.1524)
				(type default)
			)
			(layer "B.SilkS")
		)
		(fp_line
			(start -1.2192 2.06756)
			(end 1.2192 2.06756)
			(stroke
				(width 0.1524)
				(type default)
			)
			(layer "B.SilkS")
		)
		(fp_line
			(start 1.2192 -2.06756)
			(end -1.2192 -2.06756)
			(stroke
				(width 0.1524)
				(type default)
			)
			(layer "B.SilkS")
		)
		(fp_line
			(start 1.2192 2.06756)
			(end 1.2192 -2.06756)
			(stroke
				(width 0.1524)
				(type default)
			)
			(layer "B.SilkS")
		)
		(pad "" np_thru_hole circle
			(at -3.4671 -1.27 270)
			(size 1.0414 1.0414)
			(drill 1.0414)
			(layers "*.Cu" "*.Mask")
			(clearance 0.381)
			(thermal_gap 0.381)
		)
		(pad "" np_thru_hole circle
			(at -3.4671 1.27 270)
			(size 1.0414 1.0414)
			(drill 1.0414)
			(layers "*.Cu" "*.Mask")
			(clearance 0.381)
			(thermal_gap 0.381)
		)
		(pad "" np_thru_hole circle
			(at 2.8829 -1.27 270)
			(size 1.0414 1.0414)
			(drill 1.0414)
			(layers "*.Cu" "*.Mask")
			(clearance 0.381)
			(thermal_gap 0.381)
		)
		(pad "" np_thru_hole circle
			(at 2.8829 1.27 270)
			(size 1.0414 1.0414)
			(drill 1.0414)
			(layers "*.Cu" "*.Mask")
			(clearance 0.381)
			(thermal_gap 0.381)
		)
		(pad "1" smd rect
			(at -0.8255 -0.249936 270)
			(size 0.3048 0.508)
			(layers "B.Cu" "B.Mask" "B.Paste")
			(net "DELTA_L_85_5INCH_BOT_DP")
		)
		(pad "2" smd rect
			(at -0.8255 0.249936 270)
			(size 0.3048 0.508)
			(layers "B.Cu" "B.Mask" "B.Paste")
			(net "DELTA_L_85_5INCH_BOT_DN")
		)
		(pad "3" smd circle
			(at 0 0 180)
			(size 0 0)
			(layers "B.Cu" "B.Mask" "B.Paste")
			(net "DELTA_L_GND_1")
		)
		(zone
			(layers "F.Cu" "B.Cu" "In1.Cu" "In2.Cu" "In3.Cu" "In4.Cu" "In5.Cu" "In6.Cu"
				"In7.Cu" "In8.Cu" "In9.Cu" "In10.Cu" "In11.Cu" "In12.Cu" "In13.Cu" "In14.Cu"
				"In15.Cu" "In16.Cu"
			)
			(hatch none 0.5)
			(connect_pads
				(clearance 0)
			)
			(min_thickness 0.25)
			(keepout
				(tracks not_allowed)
				(vias allowed)
				(pads allowed)
				(copperpour not_allowed)
				(footprints allowed)
			)
			(placement
				(enabled no)
				(sheetname "")
			)
			(fill
				(thermal_gap 0.5)
				(thermal_bridge_width 0.5)
				(island_removal_mode 0)
			)
			(polygon
				(pts
					(arc
						(start 363.748574 1.272794)
						(mid 361.894374 1.272794)
						(end 363.748574 1.272794)
					)
				)
			)
		)
		(zone
			(layers "F.Cu" "B.Cu" "In1.Cu" "In2.Cu" "In3.Cu" "In4.Cu" "In5.Cu" "In6.Cu"
				"In7.Cu" "In8.Cu" "In9.Cu" "In10.Cu" "In11.Cu" "In12.Cu" "In13.Cu" "In14.Cu"
				"In15.Cu" "In16.Cu"
			)
			(hatch none 0.5)
			(connect_pads
				(clearance 0)
			)
			(min_thickness 0.25)
			(keepout
				(tracks not_allowed)
				(vias allowed)
				(pads allowed)
				(copperpour not_allowed)
				(footprints allowed)
			)
			(placement
				(enabled no)
				(sheetname "")
			)
			(fill
				(thermal_gap 0.5)
				(thermal_bridge_width 0.5)
				(island_removal_mode 0)
			)
			(polygon
				(pts
					(arc
						(start 363.748574 3.812794)
						(mid 361.894374 3.812794)
						(end 363.748574 3.812794)
					)
				)
			)
		)
		(zone
			(layers "F.Cu" "B.Cu" "In1.Cu" "In2.Cu" "In3.Cu" "In4.Cu" "In5.Cu" "In6.Cu"
				"In7.Cu" "In8.Cu" "In9.Cu" "In10.Cu" "In11.Cu" "In12.Cu" "In13.Cu" "In14.Cu"
				"In15.Cu" "In16.Cu"
			)
			(hatch none 0.5)
			(connect_pads
				(clearance 0)
			)
			(min_thickness 0.25)
			(keepout
				(tracks not_allowed)
				(vias allowed)
				(pads allowed)
				(copperpour not_allowed)
				(footprints allowed)
			)
			(placement
				(enabled no)
				(sheetname "")
			)
			(fill
				(thermal_gap 0.5)
				(thermal_bridge_width 0.5)
				(island_removal_mode 0)
			)
			(polygon
				(pts
					(arc
						(start 370.098574 1.272794)
						(mid 368.244374 1.272794)
						(end 370.098574 1.272794)
					)
				)
			)
		)
		(zone
			(layers "F.Cu" "B.Cu" "In1.Cu" "In2.Cu" "In3.Cu" "In4.Cu" "In5.Cu" "In6.Cu"
				"In7.Cu" "In8.Cu" "In9.Cu" "In10.Cu" "In11.Cu" "In12.Cu" "In13.Cu" "In14.Cu"
				"In15.Cu" "In16.Cu"
			)
			(hatch none 0.5)
			(connect_pads
				(clearance 0)
			)
			(min_thickness 0.25)
			(keepout
				(tracks not_allowed)
				(vias allowed)
				(pads allowed)
				(copperpour not_allowed)
				(footprints allowed)
			)
			(placement
				(enabled no)
				(sheetname "")
			)
			(fill
				(thermal_gap 0.5)
				(thermal_bridge_width 0.5)
				(island_removal_mode 0)
			)
			(polygon
				(pts
					(arc
						(start 370.098574 3.812794)
						(mid 368.244374 3.812794)
						(end 370.098574 3.812794)
					)
				)
			)
		)
		(zone
			(layer "B.Cu")
			(hatch none 0.5)
			(connect_pads
				(clearance 0)
			)
			(min_thickness 0.25)
			(keepout
				(tracks not_allowed)
				(vias allowed)
				(pads allowed)
				(copperpour not_allowed)
				(footprints allowed)
			)
			(placement
				(enabled no)
				(sheetname "")
			)
			(fill
				(thermal_gap 0.5)
				(thermal_bridge_width 0.5)
				(island_removal_mode 0)
			)
			(polygon
				(pts
					(xy 365.170974 1.994154) (xy 365.170974 2.089658) (xy 365.767874 2.089658) (xy 365.767874 2.496058)
					(xy 365.170974 2.496058) (xy 365.170974 2.58953) (xy 365.767874 2.58953) (xy 365.767874 2.99593)
					(xy 365.170974 2.99593) (xy 365.170974 3.091434) (xy 365.869474 3.091434) (xy 365.869474 1.994154)
				)
			)
		)
	)
	(footprint ""
		(layer "B.Cu")
		(at 287.149286 -427.37151)
		(property "Reference" "R2676"
			(at 0 0 0)
			(layer "B.SilkS")
			(hide yes)
			(effects
				(font
					(size 1.27 1.27)
				)
				(justify mirror)
			)
		)
		(property "Value" ""
			(at 0 0 0)
			(layer "B.Fab")
			(effects
				(font
					(size 1.27 1.27)
				)
				(justify mirror)
			)
		)
		(duplicate_pad_numbers_are_jumpers no)
		(fp_line
			(start -0.7874 -0.4064)
			(end -0.7874 0.4064)
			(stroke
				(width 0.1524)
				(type default)
			)
			(layer "B.SilkS")
		)
		(fp_line
			(start -0.7874 0.4064)
			(end 0.7874 0.4064)
			(stroke
				(width 0.1524)
				(type default)
			)
			(layer "B.SilkS")
		)
		(fp_line
			(start 0.7874 -0.4064)
			(end -0.7874 -0.4064)
			(stroke
				(width 0.1524)
				(type default)
			)
			(layer "B.SilkS")
		)
		(fp_line
			(start 0.7874 0.4064)
			(end 0.7874 -0.4064)
			(stroke
				(width 0.1524)
				(type default)
			)
			(layer "B.SilkS")
		)
		(fp_line
			(start -0.67945 -0.3048)
			(end -0.67945 0.3048)
			(stroke
				(width 0.1)
				(type default)
			)
			(layer "B.Fab")
		)
		(fp_line
			(start -0.67945 0.3048)
			(end -0.120396 0.3048)
			(stroke
				(width 0.1)
				(type default)
			)
			(layer "B.Fab")
		)
		(fp_line
			(start -0.12065 -0.3048)
			(end -0.67945 -0.3048)
			(stroke
				(width 0.1)
				(type default)
			)
			(layer "B.Fab")
		)
		(fp_line
			(start -0.12065 -0.2794)
			(end -0.12065 -0.3048)
			(stroke
				(width 0.1)
				(type default)
			)
			(layer "B.Fab")
		)
		(fp_line
			(start -0.120396 0.2794)
			(end 0.12065 0.2794)
			(stroke
				(width 0.1)
				(type default)
			)
			(layer "B.Fab")
		)
		(fp_line
			(start -0.120396 0.3048)
			(end -0.120396 0.2794)
			(stroke
				(width 0.1)
				(type default)
			)
			(layer "B.Fab")
		)
		(fp_line
			(start 0.12065 -0.305054)
			(end 0.12065 -0.2794)
			(stroke
				(width 0.1)
				(type default)
			)
			(layer "B.Fab")
		)
		(fp_line
			(start 0.12065 -0.2794)
			(end -0.12065 -0.2794)
			(stroke
				(width 0.1)
				(type default)
			)
			(layer "B.Fab")
		)
		(fp_line
			(start 0.12065 0.2794)
			(end 0.12065 0.3048)
			(stroke
				(width 0.1)
				(type default)
			)
			(layer "B.Fab")
		)
		(fp_line
			(start 0.12065 0.3048)
			(end 0.67945 0.3048)
			(stroke
				(width 0.1)
				(type default)
			)
			(layer "B.Fab")
		)
		(fp_line
			(start 0.67945 -0.305054)
			(end 0.12065 -0.305054)
			(stroke
				(width 0.1)
				(type default)
			)
			(layer "B.Fab")
		)
		(fp_line
			(start 0.67945 0.3048)
			(end 0.67945 -0.305054)
			(stroke
				(width 0.1)
				(type default)
			)
			(layer "B.Fab")
		)
		(pad "1" smd circle
			(at 0.40005 0 180)
			(size 0 0)
			(layers "B.Cu" "B.Mask" "B.Paste")
			(net "SMB_BMC_SWB_EN")
		)
		(pad "2" smd circle
			(at -0.40005 0 180)
			(size 0 0)
			(layers "B.Cu" "B.Mask" "B.Paste")
			(net "SMB_BMC_SWB_EN_R2")
		)
	)
	(footprint ""
		(layer "B.Cu")
		(at 377.488958 -208.530952 -90)
		(property "Reference" "R401"
			(at 0 0 90)
			(layer "B.SilkS")
			(hide yes)
			(effects
				(font
					(size 1.27 1.27)
				)
				(justify mirror)
			)
		)
		(property "Value" ""
			(at 0 0 90)
			(layer "B.Fab")
			(effects
				(font
					(size 1.27 1.27)
				)
				(justify mirror)
			)
		)
		(duplicate_pad_numbers_are_jumpers no)
		(fp_line
			(start -0.7874 0.4064)
			(end 0.7874 0.4064)
			(stroke
				(width 0.1524)
				(type default)
			)
			(layer "B.SilkS")
		)
		(fp_line
			(start 0.7874 0.4064)
			(end 0.7874 -0.4064)
			(stroke
				(width 0.1524)
				(type default)
			)
			(layer "B.SilkS")
		)
		(fp_line
			(start -0.7874 -0.4064)
			(end -0.7874 0.4064)
			(stroke
				(width 0.1524)
				(type default)
			)
			(layer "B.SilkS")
		)
		(fp_line
			(start 0.7874 -0.4064)
			(end -0.7874 -0.4064)
			(stroke
				(width 0.1524)
				(type default)
			)
			(layer "B.SilkS")
		)
		(fp_line
			(start -0.67945 0.3048)
			(end -0.120396 0.3048)
			(stroke
				(width 0.1)
				(type default)
			)
			(layer "B.Fab")
		)
		(fp_line
			(start -0.120396 0.3048)
			(end -0.120396 0.2794)
			(stroke
				(width 0.1)
				(type default)
			)
			(layer "B.Fab")
		)
		(fp_line
			(start 0.12065 0.3048)
			(end 0.67945 0.3048)
			(stroke
				(width 0.1)
				(type default)
			)
			(layer "B.Fab")
		)
		(fp_line
			(start 0.67945 0.3048)
			(end 0.67945 -0.305054)
			(stroke
				(width 0.1)
				(type default)
			)
			(layer "B.Fab")
		)
		(fp_line
			(start -0.120396 0.2794)
			(end 0.12065 0.2794)
			(stroke
				(width 0.1)
				(type default)
			)
			(layer "B.Fab")
		)
		(fp_line
			(start 0.12065 0.2794)
			(end 0.12065 0.3048)
			(stroke
				(width 0.1)
				(type default)
			)
			(layer "B.Fab")
		)
		(fp_line
			(start -0.12065 -0.2794)
			(end -0.12065 -0.3048)
			(stroke
				(width 0.1)
				(type default)
			)
			(layer "B.Fab")
		)
		(fp_line
			(start 0.12065 -0.2794)
			(end -0.12065 -0.2794)
			(stroke
				(width 0.1)
				(type default)
			)
			(layer "B.Fab")
		)
		(fp_line
			(start -0.67945 -0.3048)
			(end -0.67945 0.3048)
			(stroke
				(width 0.1)
				(type default)
			)
			(layer "B.Fab")
		)
		(fp_line
			(start -0.12065 -0.3048)
			(end -0.67945 -0.3048)
			(stroke
				(width 0.1)
				(type default)
			)
			(layer "B.Fab")
		)
		(fp_line
			(start 0.12065 -0.305054)
			(end 0.12065 -0.2794)
			(stroke
				(width 0.1)
				(type default)
			)
			(layer "B.Fab")
		)
		(fp_line
			(start 0.67945 -0.305054)
			(end 0.12065 -0.305054)
			(stroke
				(width 0.1)
				(type default)
			)
			(layer "B.Fab")
		)
		(pad "1" smd circle
			(at 0.40005 0 90)
			(size 0 0)
			(layers "B.Cu" "B.Mask" "B.Paste")
			(net "PVDD18_S5_P0")
		)
		(pad "2" smd circle
			(at -0.40005 0 90)
			(size 0 0)
			(layers "B.Cu" "B.Mask" "B.Paste")
			(net "JTAG_CPU0_TCK")
		)
	)
	(footprint ""
		(layer "B.Cu")
		(at 384.113278 -140.202158 180)
		(property "Reference" "PC462"
			(at 0 0 0)
			(layer "B.SilkS")
			(hide yes)
			(effects
				(font
					(size 1.27 1.27)
				)
				(justify mirror)
			)
		)
		(property "Value" ""
			(at 0 0 0)
			(layer "B.Fab")
			(effects
				(font
					(size 1.27 1.27)
				)
				(justify mirror)
			)
		)
		(duplicate_pad_numbers_are_jumpers no)
		(fp_line
			(start 0.7874 0.4064)
			(end 0.7874 -0.4064)
			(stroke
				(width 0.1524)
				(type default)
			)
			(layer "B.SilkS")
		)
		(fp_line
			(start 0.7874 -0.4064)
			(end -0.7874 -0.4064)
			(stroke
				(width 0.1524)
				(type default)
			)
			(layer "B.SilkS")
		)
		(fp_line
			(start -0.7874 0.4064)
			(end 0.7874 0.4064)
			(stroke
				(width 0.1524)
				(type default)
			)
			(layer "B.SilkS")
		)
		(fp_line
			(start -0.7874 -0.4064)
			(end -0.7874 0.4064)
			(stroke
				(width 0.1524)
				(type default)
			)
			(layer "B.SilkS")
		)
		(fp_line
			(start 0.67945 0.3048)
			(end 0.67945 -0.305054)
			(stroke
				(width 0.1)
				(type default)
			)
			(layer "B.Fab")
		)
		(fp_line
			(start 0.67945 -0.305054)
			(end 0.12065 -0.305054)
			(stroke
				(width 0.1)
				(type default)
			)
			(layer "B.Fab")
		)
		(fp_line
			(start 0.12065 0.3048)
			(end 0.67945 0.3048)
			(stroke
				(width 0.1)
				(type default)
			)
			(layer "B.Fab")
		)
		(fp_line
			(start 0.12065 0.2794)
			(end 0.12065 0.3048)
			(stroke
				(width 0.1)
				(type default)
			)
			(layer "B.Fab")
		)
		(fp_line
			(start 0.12065 -0.2794)
			(end -0.12065 -0.2794)
			(stroke
				(width 0.1)
				(type default)
			)
			(layer "B.Fab")
		)
		(fp_line
			(start 0.12065 -0.305054)
			(end 0.12065 -0.2794)
			(stroke
				(width 0.1)
				(type default)
			)
			(layer "B.Fab")
		)
		(fp_line
			(start -0.120396 0.3048)
			(end -0.120396 0.2794)
			(stroke
				(width 0.1)
				(type default)
			)
			(layer "B.Fab")
		)
		(fp_line
			(start -0.120396 0.2794)
			(end 0.12065 0.2794)
			(stroke
				(width 0.1)
				(type default)
			)
			(layer "B.Fab")
		)
		(fp_line
			(start -0.12065 -0.2794)
			(end -0.12065 -0.3048)
			(stroke
				(width 0.1)
				(type default)
			)
			(layer "B.Fab")
		)
		(fp_line
			(start -0.12065 -0.3048)
			(end -0.67945 -0.3048)
			(stroke
				(width 0.1)
				(type default)
			)
			(layer "B.Fab")
		)
		(fp_line
			(start -0.67945 0.3048)
			(end -0.120396 0.3048)
			(stroke
				(width 0.1)
				(type default)
			)
			(layer "B.Fab")
		)
		(fp_line
			(start -0.67945 -0.3048)
			(end -0.67945 0.3048)
			(stroke
				(width 0.1)
				(type default)
			)
			(layer "B.Fab")
		)
		(pad "1" smd circle
			(at 0.40005 0)
			(size 0 0)
			(layers "B.Cu" "B.Mask" "B.Paste")
			(net "PVDDCR_CPU0_P0_VMON")
		)
		(pad "2" smd circle
			(at -0.40005 0)
			(size 0 0)
			(layers "B.Cu" "B.Mask" "B.Paste")
			(net "GND")
		)
	)
	(footprint ""
		(layer "B.Cu")
		(at 94.488 -303.748948)
		(property "Reference" "R545"
			(at 0 0 0)
			(layer "B.SilkS")
			(hide yes)
			(effects
				(font
					(size 1.27 1.27)
				)
				(justify mirror)
			)
		)
		(property "Value" ""
			(at 0 0 0)
			(layer "B.Fab")
			(effects
				(font
					(size 1.27 1.27)
				)
				(justify mirror)
			)
		)
		(duplicate_pad_numbers_are_jumpers no)
		(fp_line
			(start -0.7874 -0.4064)
			(end -0.7874 0.4064)
			(stroke
				(width 0.1524)
				(type default)
			)
			(layer "B.SilkS")
		)
		(fp_line
			(start -0.7874 0.4064)
			(end 0.7874 0.4064)
			(stroke
				(width 0.1524)
				(type default)
			)
			(layer "B.SilkS")
		)
		(fp_line
			(start 0.7874 -0.4064)
			(end -0.7874 -0.4064)
			(stroke
				(width 0.1524)
				(type default)
			)
			(layer "B.SilkS")
		)
		(fp_line
			(start 0.7874 0.4064)
			(end 0.7874 -0.4064)
			(stroke
				(width 0.1524)
				(type default)
			)
			(layer "B.SilkS")
		)
		(fp_line
			(start -0.67945 -0.3048)
			(end -0.67945 0.3048)
			(stroke
				(width 0.1)
				(type default)
			)
			(layer "B.Fab")
		)
		(fp_line
			(start -0.67945 0.3048)
			(end -0.120396 0.3048)
			(stroke
				(width 0.1)
				(type default)
			)
			(layer "B.Fab")
		)
		(fp_line
			(start -0.12065 -0.3048)
			(end -0.67945 -0.3048)
			(stroke
				(width 0.1)
				(type default)
			)
			(layer "B.Fab")
		)
		(fp_line
			(start -0.12065 -0.2794)
			(end -0.12065 -0.3048)
			(stroke
				(width 0.1)
				(type default)
			)
			(layer "B.Fab")
		)
		(fp_line
			(start -0.120396 0.2794)
			(end 0.12065 0.2794)
			(stroke
				(width 0.1)
				(type default)
			)
			(layer "B.Fab")
		)
		(fp_line
			(start -0.120396 0.3048)
			(end -0.120396 0.2794)
			(stroke
				(width 0.1)
				(type default)
			)
			(layer "B.Fab")
		)
		(fp_line
			(start 0.12065 -0.305054)
			(end 0.12065 -0.2794)
			(stroke
				(width 0.1)
				(type default)
			)
			(layer "B.Fab")
		)
		(fp_line
			(start 0.12065 -0.2794)
			(end -0.12065 -0.2794)
			(stroke
				(width 0.1)
				(type default)
			)
			(layer "B.Fab")
		)
		(fp_line
			(start 0.12065 0.2794)
			(end 0.12065 0.3048)
			(stroke
				(width 0.1)
				(type default)
			)
			(layer "B.Fab")
		)
		(fp_line
			(start 0.12065 0.3048)
			(end 0.67945 0.3048)
			(stroke
				(width 0.1)
				(type default)
			)
			(layer "B.Fab")
		)
		(fp_line
			(start 0.67945 -0.305054)
			(end 0.12065 -0.305054)
			(stroke
				(width 0.1)
				(type default)
			)
			(layer "B.Fab")
		)
		(fp_line
			(start 0.67945 0.3048)
			(end 0.67945 -0.305054)
			(stroke
				(width 0.1)
				(type default)
			)
			(layer "B.Fab")
		)
		(pad "1" smd circle
			(at 0.40005 0 180)
			(size 0 0)
			(layers "B.Cu" "B.Mask" "B.Paste")
			(net "FM_BMC_READY_N")
		)
		(pad "2" smd circle
			(at -0.40005 0 180)
			(size 0 0)
			(layers "B.Cu" "B.Mask" "B.Paste")
			(net "PVDD18_S5_P1")
		)
	)
)
